# BASEBOARD_FAB2 (Tioga Pass) — schematic netlist excerpt (pin names and nets, part order shuffled) for the footprints in the layout excerpt that follows; sources: Cadence DE-HDL packaged netlist, KiCad conversion of Wiwynn_Tioga_Pass_MB.brd

C7B25  CAP  0.22UF 16V 10% X7R  pkg 0402  page 129 : A = DMI_CPU0_PCH_TX_DP<3> ; B = DMI_CPU0_PCH_TX_C_DP<3>

EU4A1  MIC5166  IC  pkg DFN  page 222
  VREF  = VR_PVTT_DEF_VREF
  BIAS  = VR_PVTT_DEF_BIAS
  AGND  = GND
  VDDQ  = VSENSE_PVDDQ_DEF_VTT
  PG  = PWRGD_PVTT_DEF_CPU0_R
  SNS  = VR_PVTT_DEF_SNS
  EN  = FM_PVTT_DEF_EN_R
  PGND  = GND
  VTT  = PVTT_DEF
  VIN  = PVDDQ_DEF
  THPAD  = GND

C6D5  CAP_A  22.0UF 4V 20% X6S  pkg 0603V  page 42 : A = PVCCMCP_CPU0 ; B = GND

(kicad_pcb
	(version 20260206)
	(generator "pcbnew")
	(generator_version "10.0")
	(general
		(thickness 1.6)
		(legacy_teardrops no)
	)
	(paper "A4")
	(title_block
		(title "Wiwynn_Tioga_Pass_MB.brd")
		(comment 1 "Tioga Pass / footprints 2012-2014 of 4770")
	)
	(layers
		(0 "F.Cu" signal "TOP")
		(4 "In1.Cu" signal "L2GND")
		(6 "In2.Cu" signal "L3")
		(8 "In3.Cu" signal "L4GND")
		(10 "In4.Cu" signal "L5")
		(12 "In5.Cu" signal "L6GND")
		(14 "In6.Cu" signal "L7VCC")
		(16 "In7.Cu" signal "L8VCC")
		(18 "In8.Cu" signal "L9GND")
		(20 "In9.Cu" signal "L10")
		(22 "In10.Cu" signal "L11GND")
		(24 "In11.Cu" signal "L12")
		(26 "In12.Cu" signal "L13GND")
		(2 "B.Cu" signal "BOTTOM")
		(9 "F.Adhes" user "F.Adhesive")
		(11 "B.Adhes" user "B.Adhesive")
		(13 "F.Paste" user "Package Geometry/Pastemask Top")
		(15 "B.Paste" user "Package Geometry/Pastemask Bottom")
		(5 "F.SilkS" user "Ref Des/Silkscreen Top")
		(7 "B.SilkS" user "Ref Des/Silkscreen Bottom")
		(1 "F.Mask" user "Board Geometry/Soldermask Top")
		(3 "B.Mask" user "Board Geometry/Soldermask Bottom")
		(17 "Dwgs.User" user "User.Drawings")
		(19 "Cmts.User" user "User.Comments")
		(21 "Eco1.User" user "User.Eco1")
		(23 "Eco2.User" user "User.Eco2")
		(25 "Edge.Cuts" user "Board Geometry/Outline")
		(27 "Margin" user)
		(31 "F.CrtYd" user "Package Geometry/Place Bound Top")
		(29 "B.CrtYd" user "Package Geometry/Place Bound Bottom")
		(35 "F.Fab" user "Ref Des/Assembly Top")
		(33 "B.Fab" user "Ref Des/Assembly Bottom")
	)
	(footprint ""
		(layer "F.Cu")
		(at 364.617 -115.189 90)
		(property "Reference" "C7B25"
			(at 0 0 90)
			(layer "F.SilkS")
			(hide yes)
			(effects
				(font
					(size 1.27 1.27)
				)
			)
		)
		(property "Value" ""
			(at 0 0 90)
			(layer "F.Fab")
			(effects
				(font
					(size 1.27 1.27)
				)
			)
		)
		(duplicate_pad_numbers_are_jumpers no)
		(fp_poly
			(pts
				(xy 0.3048 -0.1016) (xy 0.3048 0.9906) (xy -0.3048 0.9906) (xy -0.3048 -0.1016)
			)
			(stroke
				(width 0)
				(type default)
			)
			(fill no)
			(layer "F.CrtYd")
		)
		(fp_line
			(start 0.3048 -0.1016)
			(end -0.3048 -0.1016)
			(stroke
				(width 0.1)
				(type default)
			)
			(layer "F.Fab")
		)
		(fp_line
			(start -0.3048 -0.1016)
			(end -0.3048 0.9906)
			(stroke
				(width 0.1)
				(type default)
			)
			(layer "F.Fab")
		)
		(fp_line
			(start 0.3048 0.9906)
			(end 0.3048 -0.1016)
			(stroke
				(width 0.1)
				(type default)
			)
			(layer "F.Fab")
		)
		(fp_line
			(start -0.3048 0.9906)
			(end 0.3048 0.9906)
			(stroke
				(width 0.1)
				(type default)
			)
			(layer "F.Fab")
		)
		(pad "1" smd rect
			(at 0 0 90)
			(size 0.508 0.508)
			(layers "F.Cu" "F.Mask" "F.Paste")
			(net "DMI_CPU0_PCH_TX_DP<3>")
		)
		(pad "2" smd rect
			(at 0 0.889 90)
			(size 0.508 0.508)
			(layers "F.Cu" "F.Mask" "F.Paste")
			(net "DMI_CPU0_PCH_TX_C_DP<3>")
		)
		(zone
			(layer "F.Cu")
			(hatch none 0.5)
			(connect_pads
				(clearance 0)
			)
			(min_thickness 0.25)
			(keepout
				(tracks allowed)
				(vias not_allowed)
				(pads allowed)
				(copperpour not_allowed)
				(footprints allowed)
			)
			(placement
				(enabled no)
				(sheetname "")
			)
			(fill
				(thermal_gap 0.5)
				(thermal_bridge_width 0.5)
				(island_removal_mode 0)
			)
			(polygon
				(pts
					(xy 364.871 -114.935) (xy 364.871 -115.443) (xy 365.252 -115.443) (xy 365.252 -114.935)
				)
			)
		)
		(zone
			(layer "F.Cu")
			(hatch none 0.5)
			(connect_pads
				(clearance 0)
			)
			(min_thickness 0.25)
			(keepout
				(tracks not_allowed)
				(vias allowed)
				(pads allowed)
				(copperpour not_allowed)
				(footprints allowed)
			)
			(placement
				(enabled no)
				(sheetname "")
			)
			(fill
				(thermal_gap 0.5)
				(thermal_bridge_width 0.5)
				(island_removal_mode 0)
			)
			(polygon
				(pts
					(xy 365.252 -114.935) (xy 365.252 -115.443) (xy 364.871 -115.443) (xy 364.871 -114.935)
				)
			)
		)
	)
	(footprint ""
		(layer "F.Cu")
		(at 181.890924 -148.3487 90)
		(property "Reference" "EU4A1"
			(at -0.2667 3.555746 90)
			(unlocked yes)
			(layer "F.SilkS")
			(effects
				(font
					(size 0.7874 0.5842)
					(thickness 0.1524)
				)
				(justify left)
			)
		)
		(property "Value" ""
			(at 0 0 90)
			(layer "F.Fab")
			(effects
				(font
					(size 1.27 1.27)
				)
			)
		)
		(duplicate_pad_numbers_are_jumpers no)
		(fp_circle
			(center -0.835152 -0.417322)
			(end -0.835152 -0.290576)
			(stroke
				(width 0.254)
				(type default)
			)
			(fill no)
			(layer "F.SilkS")
		)
		(fp_poly
			(pts
				(xy -0.064516 -1.0922) (xy -0.064516 -0.3302) (xy 0.697484 -1.0922)
			)
			(stroke
				(width 0)
				(type default)
			)
			(fill yes)
			(layer "F.SilkS")
		)
		(fp_rect
			(start 0.597408 2.295398)
			(end 2.273808 -0.295402)
			(stroke
				(width 0)
				(type default)
			)
			(fill yes)
			(layer "F.Paste")
		)
		(fp_rect
			(start -0.064516 2.500122)
			(end 2.935478 -0.500126)
			(stroke
				(width 0)
				(type default)
			)
			(fill no)
			(layer "F.CrtYd")
		)
		(fp_line
			(start 2.935478 -0.500126)
			(end 2.935478 2.500122)
			(stroke
				(width 0.1)
				(type default)
			)
			(layer "F.Fab")
		)
		(fp_line
			(start -0.064516 -0.500126)
			(end 2.935478 -0.500126)
			(stroke
				(width 0.1)
				(type default)
			)
			(layer "F.Fab")
		)
		(fp_line
			(start 2.935478 2.500122)
			(end -0.064516 2.500122)
			(stroke
				(width 0.1)
				(type default)
			)
			(layer "F.Fab")
		)
		(fp_line
			(start -0.064516 2.500122)
			(end -0.064516 -0.500126)
			(stroke
				(width 0.1)
				(type default)
			)
			(layer "F.Fab")
		)
		(fp_circle
			(center -0.835152 -0.417322)
			(end -0.835152 -0.290576)
			(stroke
				(width 0.254)
				(type default)
			)
			(fill no)
			(layer "F.Fab")
		)
		(pad "1" smd rect
			(at 0 0 90)
			(size 0.6858 0.3048)
			(layers "F.Cu" "F.Mask" "F.Paste")
			(net "VR_PVTT_DEF_VREF")
		)
		(pad "2" smd rect
			(at 0 0.500126 90)
			(size 0.6858 0.3048)
			(layers "F.Cu" "F.Mask" "F.Paste")
			(net "VR_PVTT_DEF_BIAS")
		)
		(pad "3" smd rect
			(at 0 0.999998 90)
			(size 0.6858 0.3048)
			(layers "F.Cu" "F.Mask" "F.Paste")
			(net "GND")
		)
		(pad "4" smd rect
			(at 0 1.500124 90)
			(size 0.6858 0.3048)
			(layers "F.Cu" "F.Mask" "F.Paste")
			(net "VSENSE_PVDDQ_DEF_VTT")
		)
		(pad "5" smd rect
			(at 0 1.999996 90)
			(size 0.6858 0.3048)
			(layers "F.Cu" "F.Mask" "F.Paste")
			(net "PWRGD_PVTT_DEF_CPU0_R")
		)
		(pad "6" smd rect
			(at 2.871216 1.999996 90)
			(size 0.6858 0.3048)
			(layers "F.Cu" "F.Mask" "F.Paste")
			(net "VR_PVTT_DEF_SNS")
		)
		(pad "7" smd rect
			(at 2.871216 1.500124 90)
			(size 0.6858 0.3048)
			(layers "F.Cu" "F.Mask" "F.Paste")
			(net "FM_PVTT_DEF_EN_R")
		)
		(pad "8" smd rect
			(at 2.871216 0.999998 90)
			(size 0.6858 0.3048)
			(layers "F.Cu" "F.Mask" "F.Paste")
			(net "GND")
		)
		(pad "9" smd rect
			(at 2.871216 0.500126 90)
			(size 0.6858 0.3048)
			(layers "F.Cu" "F.Mask" "F.Paste")
			(net "PVTT_DEF")
		)
		(pad "10" smd rect
			(at 2.871216 0 90)
			(size 0.6858 0.3048)
			(layers "F.Cu" "F.Mask" "F.Paste")
			(net "PVDDQ_DEF")
		)
		(pad "11" smd rect
			(at 1.435608 0.999998 90)
			(size 1.6764 2.5908)
			(layers "F.Cu" "F.Mask" "F.Paste")
			(net "GND")
		)
	)
	(footprint ""
		(layer "F.Cu")
		(at 277.182834 -77.382116)
		(property "Reference" "C6D5"
			(at 0 0 0)
			(layer "F.SilkS")
			(hide yes)
			(effects
				(font
					(size 1.27 1.27)
				)
			)
		)
		(property "Value" ""
			(at 0 0 0)
			(layer "F.Fab")
			(effects
				(font
					(size 1.27 1.27)
				)
			)
		)
		(duplicate_pad_numbers_are_jumpers no)
		(fp_poly
			(pts
				(xy -0.4953 -0.2032) (xy 0.4953 -0.2032) (xy 0.4953 1.6002) (xy -0.4953 1.6002)
			)
			(stroke
				(width 0)
				(type default)
			)
			(fill no)
			(layer "F.CrtYd")
		)
		(fp_line
			(start -0.4953 -0.2032)
			(end 0.4953 -0.2032)
			(stroke
				(width 0.1)
				(type default)
			)
			(layer "F.Fab")
		)
		(fp_line
			(start -0.4953 1.6002)
			(end -0.4953 -0.2032)
			(stroke
				(width 0.1)
				(type default)
			)
			(layer "F.Fab")
		)
		(fp_line
			(start 0.4953 -0.2032)
			(end 0.4953 1.6002)
			(stroke
				(width 0.1)
				(type default)
			)
			(layer "F.Fab")
		)
		(fp_line
			(start 0.4953 1.6002)
			(end -0.4953 1.6002)
			(stroke
				(width 0.1)
				(type default)
			)
			(layer "F.Fab")
		)
		(pad "1" smd rect
			(at 0 0)
			(size 0.762 0.889)
			(layers "F.Cu" "F.Mask" "F.Paste")
			(net "PVCCMCP_CPU0")
		)
		(pad "2" smd rect
			(at 0 1.397)
			(size 0.762 0.889)
			(layers "F.Cu" "F.Mask" "F.Paste")
			(net "GND")
		)
		(zone
			(layer "F.Cu")
			(hatch none 0.5)
			(connect_pads
				(clearance 0)
			)
			(min_thickness 0.25)
			(keepout
				(tracks not_allowed)
				(vias allowed)
				(pads allowed)
				(copperpour not_allowed)
				(footprints allowed)
			)
			(placement
				(enabled no)
				(sheetname "")
			)
			(fill
				(thermal_gap 0.5)
				(thermal_bridge_width 0.5)
				(island_removal_mode 0)
			)
			(polygon
				(pts
					(xy 276.801834 -76.937616) (xy 277.563834 -76.937616) (xy 277.563834 -76.429616) (xy 276.801834 -76.429616)
				)
			)
		)
	)
)
